(kicad_pcb
	(version 20260206)
	(generator "pcbnew")
	(generator_version "10.0")
	(general
		(thickness 1.6)
		(legacy_teardrops no)
	)
	(paper "A4")
	(title_block
		(title "04192023_DAF0TMB3IC0_F0TG_MB_C_brd_V02_OCP.brd")
		(comment 1 "Grand Teton / footprints 1332-1338 of 8354")
	)
	(layers
		(0 "F.Cu" signal "TOP")
		(4 "In1.Cu" signal "GND")
		(6 "In2.Cu" signal "IN1")
		(8 "In3.Cu" signal "GND1")
		(10 "In4.Cu" signal "IN2")
		(12 "In5.Cu" signal "GND2")
		(14 "In6.Cu" signal "IN3")
		(16 "In7.Cu" signal "GND3")
		(18 "In8.Cu" signal "VCC")
		(20 "In9.Cu" signal "VCC1")
		(22 "In10.Cu" signal "GND4")
		(24 "In11.Cu" signal "IN4")
		(26 "In12.Cu" signal "GND5")
		(28 "In13.Cu" signal "IN5")
		(30 "In14.Cu" signal "GND6")
		(32 "In15.Cu" signal "IN6")
		(34 "In16.Cu" signal "GND7")
		(2 "B.Cu" signal "BOTTOM")
		(9 "F.Adhes" user "F.Adhesive")
		(11 "B.Adhes" user "B.Adhesive")
		(13 "F.Paste" user "Package Geometry/Pastemask Top")
		(15 "B.Paste" user "Package Geometry/Pastemask Bottom")
		(5 "F.SilkS" user "Ref Des/Silkscreen Top")
		(7 "B.SilkS" user "Ref Des/Silkscreen Bottom")
		(1 "F.Mask" user "Board Geometry/Soldermask Top")
		(3 "B.Mask" user "Board Geometry/Soldermask Bottom")
		(17 "Dwgs.User" user "User.Drawings")
		(19 "Cmts.User" user "User.Comments")
		(21 "Eco1.User" user "User.Eco1")
		(23 "Eco2.User" user "User.Eco2")
		(25 "Edge.Cuts" user "Board Geometry/Outline")
		(27 "Margin" user)
		(31 "F.CrtYd" user "Package Geometry/Place Bound Top")
		(29 "B.CrtYd" user "Package Geometry/Place Bound Bottom")
		(35 "F.Fab" user "Ref Des/Assembly Top")
		(33 "B.Fab" user "Ref Des/Assembly Bottom")
	)
	(footprint ""
		(layer "F.Cu")
		(at 44.7294 -105.8164 180)
		(property "Reference" "R1092"
			(at 0 0 180)
			(layer "F.SilkS")
			(hide yes)
			(effects
				(font
					(size 1.27 1.27)
				)
			)
		)
		(property "Value" ""
			(at 0 0 180)
			(layer "F.Fab")
			(effects
				(font
					(size 1.27 1.27)
				)
			)
		)
		(duplicate_pad_numbers_are_jumpers no)
		(fp_line
			(start 0.7874 0.4064)
			(end -0.7874 0.4064)
			(stroke
				(width 0.1524)
				(type default)
			)
			(layer "F.SilkS")
		)
		(fp_line
			(start 0.7874 -0.4064)
			(end 0.7874 0.4064)
			(stroke
				(width 0.1524)
				(type default)
			)
			(layer "F.SilkS")
		)
		(fp_line
			(start -0.7874 0.4064)
			(end -0.7874 -0.4064)
			(stroke
				(width 0.1524)
				(type default)
			)
			(layer "F.SilkS")
		)
		(fp_line
			(start -0.7874 -0.4064)
			(end 0.7874 -0.4064)
			(stroke
				(width 0.1524)
				(type default)
			)
			(layer "F.SilkS")
		)
		(fp_line
			(start 0.67945 0.3048)
			(end 0.120396 0.3048)
			(stroke
				(width 0.1)
				(type default)
			)
			(layer "F.Fab")
		)
		(fp_line
			(start 0.67945 -0.3048)
			(end 0.67945 0.3048)
			(stroke
				(width 0.1)
				(type default)
			)
			(layer "F.Fab")
		)
		(fp_line
			(start 0.12065 -0.2794)
			(end 0.12065 -0.3048)
			(stroke
				(width 0.1)
				(type default)
			)
			(layer "F.Fab")
		)
		(fp_line
			(start 0.12065 -0.3048)
			(end 0.67945 -0.3048)
			(stroke
				(width 0.1)
				(type default)
			)
			(layer "F.Fab")
		)
		(fp_line
			(start 0.120396 0.3048)
			(end 0.120396 0.2794)
			(stroke
				(width 0.1)
				(type default)
			)
			(layer "F.Fab")
		)
		(fp_line
			(start 0.120396 0.2794)
			(end -0.12065 0.2794)
			(stroke
				(width 0.1)
				(type default)
			)
			(layer "F.Fab")
		)
		(fp_line
			(start -0.12065 0.3048)
			(end -0.67945 0.3048)
			(stroke
				(width 0.1)
				(type default)
			)
			(layer "F.Fab")
		)
		(fp_line
			(start -0.12065 0.2794)
			(end -0.12065 0.3048)
			(stroke
				(width 0.1)
				(type default)
			)
			(layer "F.Fab")
		)
		(fp_line
			(start -0.12065 -0.2794)
			(end 0.12065 -0.2794)
			(stroke
				(width 0.1)
				(type default)
			)
			(layer "F.Fab")
		)
		(fp_line
			(start -0.12065 -0.305054)
			(end -0.12065 -0.2794)
			(stroke
				(width 0.1)
				(type default)
			)
			(layer "F.Fab")
		)
		(fp_line
			(start -0.67945 0.3048)
			(end -0.67945 -0.305054)
			(stroke
				(width 0.1)
				(type default)
			)
			(layer "F.Fab")
		)
		(fp_line
			(start -0.67945 -0.305054)
			(end -0.12065 -0.305054)
			(stroke
				(width 0.1)
				(type default)
			)
			(layer "F.Fab")
		)
		(pad "1" smd circle
			(at -0.40005 0 180)
			(size 0 0)
			(layers "F.Cu" "F.Mask" "F.Paste")
			(net "P3V3_AUX_DSC_G1")
		)
		(pad "2" smd circle
			(at 0.40005 0 180)
			(size 0 0)
			(layers "F.Cu" "F.Mask" "F.Paste")
			(net "GND")
		)
	)
	(footprint ""
		(layer "F.Cu")
		(at 301.621952 -23.14575)
		(property "Reference" "R1776"
			(at 0 0 0)
			(layer "F.SilkS")
			(hide yes)
			(effects
				(font
					(size 1.27 1.27)
				)
			)
		)
		(property "Value" ""
			(at 0 0 0)
			(layer "F.Fab")
			(effects
				(font
					(size 1.27 1.27)
				)
			)
		)
		(duplicate_pad_numbers_are_jumpers no)
		(fp_line
			(start -0.7874 -0.4064)
			(end 0.7874 -0.4064)
			(stroke
				(width 0.1524)
				(type default)
			)
			(layer "F.SilkS")
		)
		(fp_line
			(start -0.7874 0.4064)
			(end -0.7874 -0.4064)
			(stroke
				(width 0.1524)
				(type default)
			)
			(layer "F.SilkS")
		)
		(fp_line
			(start 0.7874 -0.4064)
			(end 0.7874 0.4064)
			(stroke
				(width 0.1524)
				(type default)
			)
			(layer "F.SilkS")
		)
		(fp_line
			(start 0.7874 0.4064)
			(end -0.7874 0.4064)
			(stroke
				(width 0.1524)
				(type default)
			)
			(layer "F.SilkS")
		)
		(fp_line
			(start -0.67945 -0.305054)
			(end -0.12065 -0.305054)
			(stroke
				(width 0.1)
				(type default)
			)
			(layer "F.Fab")
		)
		(fp_line
			(start -0.67945 0.3048)
			(end -0.67945 -0.305054)
			(stroke
				(width 0.1)
				(type default)
			)
			(layer "F.Fab")
		)
		(fp_line
			(start -0.12065 -0.305054)
			(end -0.12065 -0.2794)
			(stroke
				(width 0.1)
				(type default)
			)
			(layer "F.Fab")
		)
		(fp_line
			(start -0.12065 -0.2794)
			(end 0.12065 -0.2794)
			(stroke
				(width 0.1)
				(type default)
			)
			(layer "F.Fab")
		)
		(fp_line
			(start -0.12065 0.2794)
			(end -0.12065 0.3048)
			(stroke
				(width 0.1)
				(type default)
			)
			(layer "F.Fab")
		)
		(fp_line
			(start -0.12065 0.3048)
			(end -0.67945 0.3048)
			(stroke
				(width 0.1)
				(type default)
			)
			(layer "F.Fab")
		)
		(fp_line
			(start 0.120396 0.2794)
			(end -0.12065 0.2794)
			(stroke
				(width 0.1)
				(type default)
			)
			(layer "F.Fab")
		)
		(fp_line
			(start 0.120396 0.3048)
			(end 0.120396 0.2794)
			(stroke
				(width 0.1)
				(type default)
			)
			(layer "F.Fab")
		)
		(fp_line
			(start 0.12065 -0.3048)
			(end 0.67945 -0.3048)
			(stroke
				(width 0.1)
				(type default)
			)
			(layer "F.Fab")
		)
		(fp_line
			(start 0.12065 -0.2794)
			(end 0.12065 -0.3048)
			(stroke
				(width 0.1)
				(type default)
			)
			(layer "F.Fab")
		)
		(fp_line
			(start 0.67945 -0.3048)
			(end 0.67945 0.3048)
			(stroke
				(width 0.1)
				(type default)
			)
			(layer "F.Fab")
		)
		(fp_line
			(start 0.67945 0.3048)
			(end 0.120396 0.3048)
			(stroke
				(width 0.1)
				(type default)
			)
			(layer "F.Fab")
		)
		(pad "1" smd circle
			(at -0.40005 0)
			(size 0 0)
			(layers "F.Cu" "F.Mask" "F.Paste")
			(net "CLR_CMOS")
		)
		(pad "2" smd circle
			(at 0.40005 0)
			(size 0 0)
			(layers "F.Cu" "F.Mask" "F.Paste")
			(net "GND")
		)
	)
	(footprint ""
		(layer "F.Cu")
		(at 156.30779 -96.012508 90)
		(property "Reference" "C1878"
			(at 0 0 90)
			(layer "F.SilkS")
			(hide yes)
			(effects
				(font
					(size 1.27 1.27)
				)
			)
		)
		(property "Value" ""
			(at 0 0 90)
			(layer "F.Fab")
			(effects
				(font
					(size 1.27 1.27)
				)
			)
		)
		(duplicate_pad_numbers_are_jumpers no)
		(fp_line
			(start 0.7874 -0.4064)
			(end 0.7874 0.4064)
			(stroke
				(width 0.1524)
				(type default)
			)
			(layer "F.SilkS")
		)
		(fp_line
			(start -0.7874 -0.4064)
			(end 0.7874 -0.4064)
			(stroke
				(width 0.1524)
				(type default)
			)
			(layer "F.SilkS")
		)
		(fp_line
			(start 0.7874 0.4064)
			(end -0.7874 0.4064)
			(stroke
				(width 0.1524)
				(type default)
			)
			(layer "F.SilkS")
		)
		(fp_line
			(start -0.7874 0.4064)
			(end -0.7874 -0.4064)
			(stroke
				(width 0.1524)
				(type default)
			)
			(layer "F.SilkS")
		)
		(fp_line
			(start -0.12065 -0.305054)
			(end -0.12065 -0.2794)
			(stroke
				(width 0.1)
				(type default)
			)
			(layer "F.Fab")
		)
		(fp_line
			(start -0.67945 -0.305054)
			(end -0.12065 -0.305054)
			(stroke
				(width 0.1)
				(type default)
			)
			(layer "F.Fab")
		)
		(fp_line
			(start 0.67945 -0.3048)
			(end 0.67945 0.3048)
			(stroke
				(width 0.1)
				(type default)
			)
			(layer "F.Fab")
		)
		(fp_line
			(start 0.12065 -0.3048)
			(end 0.67945 -0.3048)
			(stroke
				(width 0.1)
				(type default)
			)
			(layer "F.Fab")
		)
		(fp_line
			(start 0.12065 -0.2794)
			(end 0.12065 -0.3048)
			(stroke
				(width 0.1)
				(type default)
			)
			(layer "F.Fab")
		)
		(fp_line
			(start -0.12065 -0.2794)
			(end 0.12065 -0.2794)
			(stroke
				(width 0.1)
				(type default)
			)
			(layer "F.Fab")
		)
		(fp_line
			(start 0.120396 0.2794)
			(end -0.12065 0.2794)
			(stroke
				(width 0.1)
				(type default)
			)
			(layer "F.Fab")
		)
		(fp_line
			(start -0.12065 0.2794)
			(end -0.12065 0.3048)
			(stroke
				(width 0.1)
				(type default)
			)
			(layer "F.Fab")
		)
		(fp_line
			(start 0.67945 0.3048)
			(end 0.120396 0.3048)
			(stroke
				(width 0.1)
				(type default)
			)
			(layer "F.Fab")
		)
		(fp_line
			(start 0.120396 0.3048)
			(end 0.120396 0.2794)
			(stroke
				(width 0.1)
				(type default)
			)
			(layer "F.Fab")
		)
		(fp_line
			(start -0.12065 0.3048)
			(end -0.67945 0.3048)
			(stroke
				(width 0.1)
				(type default)
			)
			(layer "F.Fab")
		)
		(fp_line
			(start -0.67945 0.3048)
			(end -0.67945 -0.305054)
			(stroke
				(width 0.1)
				(type default)
			)
			(layer "F.Fab")
		)
		(pad "1" smd circle
			(at -0.40005 0 90)
			(size 0 0)
			(layers "F.Cu" "F.Mask" "F.Paste")
			(net "P3V3_AUX")
		)
		(pad "2" smd circle
			(at 0.40005 0 90)
			(size 0 0)
			(layers "F.Cu" "F.Mask" "F.Paste")
			(net "GND")
		)
	)
	(footprint ""
		(layer "F.Cu")
		(at 11.590782 -405.611584 -90)
		(property "Reference" "PC6545"
			(at 0 0 270)
			(layer "F.SilkS")
			(hide yes)
			(effects
				(font
					(size 1.27 1.27)
				)
			)
		)
		(property "Value" ""
			(at 0 0 270)
			(layer "F.Fab")
			(effects
				(font
					(size 1.27 1.27)
				)
			)
		)
		(duplicate_pad_numbers_are_jumpers no)
		(fp_line
			(start -0.7874 0.4064)
			(end -0.7874 -0.4064)
			(stroke
				(width 0.1524)
				(type default)
			)
			(layer "F.SilkS")
		)
		(fp_line
			(start 0.7874 0.4064)
			(end -0.7874 0.4064)
			(stroke
				(width 0.1524)
				(type default)
			)
			(layer "F.SilkS")
		)
		(fp_line
			(start -0.7874 -0.4064)
			(end 0.7874 -0.4064)
			(stroke
				(width 0.1524)
				(type default)
			)
			(layer "F.SilkS")
		)
		(fp_line
			(start 0.7874 -0.4064)
			(end 0.7874 0.4064)
			(stroke
				(width 0.1524)
				(type default)
			)
			(layer "F.SilkS")
		)
		(fp_line
			(start -0.67945 0.3048)
			(end -0.67945 -0.305054)
			(stroke
				(width 0.1)
				(type default)
			)
			(layer "F.Fab")
		)
		(fp_line
			(start -0.12065 0.3048)
			(end -0.67945 0.3048)
			(stroke
				(width 0.1)
				(type default)
			)
			(layer "F.Fab")
		)
		(fp_line
			(start 0.120396 0.3048)
			(end 0.120396 0.2794)
			(stroke
				(width 0.1)
				(type default)
			)
			(layer "F.Fab")
		)
		(fp_line
			(start 0.67945 0.3048)
			(end 0.120396 0.3048)
			(stroke
				(width 0.1)
				(type default)
			)
			(layer "F.Fab")
		)
		(fp_line
			(start -0.12065 0.2794)
			(end -0.12065 0.3048)
			(stroke
				(width 0.1)
				(type default)
			)
			(layer "F.Fab")
		)
		(fp_line
			(start 0.120396 0.2794)
			(end -0.12065 0.2794)
			(stroke
				(width 0.1)
				(type default)
			)
			(layer "F.Fab")
		)
		(fp_line
			(start -0.12065 -0.2794)
			(end 0.12065 -0.2794)
			(stroke
				(width 0.1)
				(type default)
			)
			(layer "F.Fab")
		)
		(fp_line
			(start 0.12065 -0.2794)
			(end 0.12065 -0.3048)
			(stroke
				(width 0.1)
				(type default)
			)
			(layer "F.Fab")
		)
		(fp_line
			(start 0.12065 -0.3048)
			(end 0.67945 -0.3048)
			(stroke
				(width 0.1)
				(type default)
			)
			(layer "F.Fab")
		)
		(fp_line
			(start 0.67945 -0.3048)
			(end 0.67945 0.3048)
			(stroke
				(width 0.1)
				(type default)
			)
			(layer "F.Fab")
		)
		(fp_line
			(start -0.67945 -0.305054)
			(end -0.12065 -0.305054)
			(stroke
				(width 0.1)
				(type default)
			)
			(layer "F.Fab")
		)
		(fp_line
			(start -0.12065 -0.305054)
			(end -0.12065 -0.2794)
			(stroke
				(width 0.1)
				(type default)
			)
			(layer "F.Fab")
		)
		(pad "1" smd circle
			(at -0.40005 0 270)
			(size 0 0)
			(layers "F.Cu" "F.Mask" "F.Paste")
			(net "PV09_RETIMER_CPU1_VCCS")
		)
		(pad "2" smd circle
			(at 0.40005 0 270)
			(size 0 0)
			(layers "F.Cu" "F.Mask" "F.Paste")
			(net "GND")
		)
	)
	(footprint ""
		(layer "F.Cu")
		(at 183.878982 -34.794952 90)
		(property "Reference" "PC2231"
			(at 0 0 90)
			(layer "F.SilkS")
			(hide yes)
			(effects
				(font
					(size 1.27 1.27)
				)
			)
		)
		(property "Value" ""
			(at 0 0 90)
			(layer "F.Fab")
			(effects
				(font
					(size 1.27 1.27)
				)
			)
		)
		(duplicate_pad_numbers_are_jumpers no)
		(fp_line
			(start 0.7874 -0.4064)
			(end 0.7874 0.4064)
			(stroke
				(width 0.1524)
				(type default)
			)
			(layer "F.SilkS")
		)
		(fp_line
			(start -0.7874 -0.4064)
			(end 0.7874 -0.4064)
			(stroke
				(width 0.1524)
				(type default)
			)
			(layer "F.SilkS")
		)
		(fp_line
			(start 0.7874 0.4064)
			(end -0.7874 0.4064)
			(stroke
				(width 0.1524)
				(type default)
			)
			(layer "F.SilkS")
		)
		(fp_line
			(start -0.7874 0.4064)
			(end -0.7874 -0.4064)
			(stroke
				(width 0.1524)
				(type default)
			)
			(layer "F.SilkS")
		)
		(fp_line
			(start -0.12065 -0.305054)
			(end -0.12065 -0.2794)
			(stroke
				(width 0.1)
				(type default)
			)
			(layer "F.Fab")
		)
		(fp_line
			(start -0.67945 -0.305054)
			(end -0.12065 -0.305054)
			(stroke
				(width 0.1)
				(type default)
			)
			(layer "F.Fab")
		)
		(fp_line
			(start 0.67945 -0.3048)
			(end 0.67945 0.3048)
			(stroke
				(width 0.1)
				(type default)
			)
			(layer "F.Fab")
		)
		(fp_line
			(start 0.12065 -0.3048)
			(end 0.67945 -0.3048)
			(stroke
				(width 0.1)
				(type default)
			)
			(layer "F.Fab")
		)
		(fp_line
			(start 0.12065 -0.2794)
			(end 0.12065 -0.3048)
			(stroke
				(width 0.1)
				(type default)
			)
			(layer "F.Fab")
		)
		(fp_line
			(start -0.12065 -0.2794)
			(end 0.12065 -0.2794)
			(stroke
				(width 0.1)
				(type default)
			)
			(layer "F.Fab")
		)
		(fp_line
			(start 0.120396 0.2794)
			(end -0.12065 0.2794)
			(stroke
				(width 0.1)
				(type default)
			)
			(layer "F.Fab")
		)
		(fp_line
			(start -0.12065 0.2794)
			(end -0.12065 0.3048)
			(stroke
				(width 0.1)
				(type default)
			)
			(layer "F.Fab")
		)
		(fp_line
			(start 0.67945 0.3048)
			(end 0.120396 0.3048)
			(stroke
				(width 0.1)
				(type default)
			)
			(layer "F.Fab")
		)
		(fp_line
			(start 0.120396 0.3048)
			(end 0.120396 0.2794)
			(stroke
				(width 0.1)
				(type default)
			)
			(layer "F.Fab")
		)
		(fp_line
			(start -0.12065 0.3048)
			(end -0.67945 0.3048)
			(stroke
				(width 0.1)
				(type default)
			)
			(layer "F.Fab")
		)
		(fp_line
			(start -0.67945 0.3048)
			(end -0.67945 -0.305054)
			(stroke
				(width 0.1)
				(type default)
			)
			(layer "F.Fab")
		)
		(pad "1" smd circle
			(at -0.40005 0 90)
			(size 0 0)
			(layers "F.Cu" "F.Mask" "F.Paste")
			(net "P12V_AUX")
		)
		(pad "2" smd circle
			(at 0.40005 0 90)
			(size 0 0)
			(layers "F.Cu" "F.Mask" "F.Paste")
			(net "GND")
		)
	)
	(footprint ""
		(layer "F.Cu")
		(at 166.934388 -346.302076 180)
		(property "Reference" "R8010"
			(at 0 0 180)
			(layer "F.SilkS")
			(hide yes)
			(effects
				(font
					(size 1.27 1.27)
				)
			)
		)
		(property "Value" ""
			(at 0 0 180)
			(layer "F.Fab")
			(effects
				(font
					(size 1.27 1.27)
				)
			)
		)
		(duplicate_pad_numbers_are_jumpers no)
		(fp_line
			(start 0.7874 0.4064)
			(end -0.7874 0.4064)
			(stroke
				(width 0.1524)
				(type default)
			)
			(layer "F.SilkS")
		)
		(fp_line
			(start 0.7874 -0.4064)
			(end 0.7874 0.4064)
			(stroke
				(width 0.1524)
				(type default)
			)
			(layer "F.SilkS")
		)
		(fp_line
			(start -0.7874 0.4064)
			(end -0.7874 -0.4064)
			(stroke
				(width 0.1524)
				(type default)
			)
			(layer "F.SilkS")
		)
		(fp_line
			(start -0.7874 -0.4064)
			(end 0.7874 -0.4064)
			(stroke
				(width 0.1524)
				(type default)
			)
			(layer "F.SilkS")
		)
		(fp_line
			(start 0.67945 0.3048)
			(end 0.120396 0.3048)
			(stroke
				(width 0.1)
				(type default)
			)
			(layer "F.Fab")
		)
		(fp_line
			(start 0.67945 -0.3048)
			(end 0.67945 0.3048)
			(stroke
				(width 0.1)
				(type default)
			)
			(layer "F.Fab")
		)
		(fp_line
			(start 0.12065 -0.2794)
			(end 0.12065 -0.3048)
			(stroke
				(width 0.1)
				(type default)
			)
			(layer "F.Fab")
		)
		(fp_line
			(start 0.12065 -0.3048)
			(end 0.67945 -0.3048)
			(stroke
				(width 0.1)
				(type default)
			)
			(layer "F.Fab")
		)
		(fp_line
			(start 0.120396 0.3048)
			(end 0.120396 0.2794)
			(stroke
				(width 0.1)
				(type default)
			)
			(layer "F.Fab")
		)
		(fp_line
			(start 0.120396 0.2794)
			(end -0.12065 0.2794)
			(stroke
				(width 0.1)
				(type default)
			)
			(layer "F.Fab")
		)
		(fp_line
			(start -0.12065 0.3048)
			(end -0.67945 0.3048)
			(stroke
				(width 0.1)
				(type default)
			)
			(layer "F.Fab")
		)
		(fp_line
			(start -0.12065 0.2794)
			(end -0.12065 0.3048)
			(stroke
				(width 0.1)
				(type default)
			)
			(layer "F.Fab")
		)
		(fp_line
			(start -0.12065 -0.2794)
			(end 0.12065 -0.2794)
			(stroke
				(width 0.1)
				(type default)
			)
			(layer "F.Fab")
		)
		(fp_line
			(start -0.12065 -0.305054)
			(end -0.12065 -0.2794)
			(stroke
				(width 0.1)
				(type default)
			)
			(layer "F.Fab")
		)
		(fp_line
			(start -0.67945 0.3048)
			(end -0.67945 -0.305054)
			(stroke
				(width 0.1)
				(type default)
			)
			(layer "F.Fab")
		)
		(fp_line
			(start -0.67945 -0.305054)
			(end -0.12065 -0.305054)
			(stroke
				(width 0.1)
				(type default)
			)
			(layer "F.Fab")
		)
		(pad "1" smd circle
			(at -0.40005 0 180)
			(size 0 0)
			(layers "F.Cu" "F.Mask" "F.Paste")
			(net "PVDD11_S3_P1_OCP_N")
		)
		(pad "2" smd circle
			(at 0.40005 0 180)
			(size 0 0)
			(layers "F.Cu" "F.Mask" "F.Paste")
			(net "PVDD11_S3_P1_OCP_N_R")
		)
	)
	(footprint ""
		(layer "F.Cu")
		(at 326.967342 -390.1694)
		(property "Reference" "R1368"
			(at 0 0 0)
			(layer "F.SilkS")
			(hide yes)
			(effects
				(font
					(size 1.27 1.27)
				)
			)
		)
		(property "Value" ""
			(at 0 0 0)
			(layer "F.Fab")
			(effects
				(font
					(size 1.27 1.27)
				)
			)
		)
		(duplicate_pad_numbers_are_jumpers no)
		(fp_line
			(start -0.32512 -0.175006)
			(end 0.32512 -0.175006)
			(stroke
				(width 0.1)
				(type default)
			)
			(layer "F.Fab")
		)
		(fp_line
			(start -0.32512 0.175006)
			(end -0.32512 -0.175006)
			(stroke
				(width 0.1)
				(type default)
			)
			(layer "F.Fab")
		)
		(fp_line
			(start 0.32512 -0.175006)
			(end 0.32512 0.175006)
			(stroke
				(width 0.1)
				(type default)
			)
			(layer "F.Fab")
		)
		(fp_line
			(start 0.32512 0.175006)
			(end -0.32512 0.175006)
			(stroke
				(width 0.1)
				(type default)
			)
			(layer "F.Fab")
		)
		(pad "1" smd rect
			(at -0.2667 0)
			(size 0.3048 0.381)
			(layers "F.Cu" "F.Mask" "F.Paste")
			(net "CLKREQ_RT_CPU0_P0_N")
		)
		(pad "2" smd rect
			(at 0.2667 0 180)
			(size 0.3048 0.381)
			(layers "F.Cu" "F.Mask" "F.Paste")
			(net "GND")
		)
	)
)
